# S9S_MB_2U (Grand Teton) — schematic netlist excerpt (pin names and nets, part order shuffled) for the footprints in the layout excerpt that follows; sources: Cadence DE-HDL packaged netlist, KiCad conversion of 03242023_DA0F0TMBIJ0_F0T_Motherboard_J_brd_V01_OCP.brd

C1039  Q_CAP  22UF 4V 20% X6S  pkg C0402  page 74 : A = PVCCIN_CPU0 ; B = GND
R3665  Q_RES  100K 1% CHIP  pkg 0402LF  page 152 : A = USB_HUB_PGANG ; B = GND

(kicad_pcb
	(version 20260206)
	(generator "pcbnew")
	(generator_version "10.0")
	(general
		(thickness 1.6)
		(legacy_teardrops no)
	)
	(paper "A4")
	(title_block
		(title "03242023_DA0F0TMBIJ0_F0T_Motherboard_J_brd_V01_OCP.brd")
		(comment 1 "Grand Teton / footprints 2293-2294 of 6105")
	)
	(layers
		(0 "F.Cu" signal "TOP")
		(4 "In1.Cu" signal "GND")
		(6 "In2.Cu" signal "IN1")
		(8 "In3.Cu" signal "GND1")
		(10 "In4.Cu" signal "IN2")
		(12 "In5.Cu" signal "GND2")
		(14 "In6.Cu" signal "IN3")
		(16 "In7.Cu" signal "GND3")
		(18 "In8.Cu" signal "VCC")
		(20 "In9.Cu" signal "VCC1")
		(22 "In10.Cu" signal "GND4")
		(24 "In11.Cu" signal "IN4")
		(26 "In12.Cu" signal "GND5")
		(28 "In13.Cu" signal "IN5")
		(30 "In14.Cu" signal "GND6")
		(32 "In15.Cu" signal "IN6")
		(34 "In16.Cu" signal "GND7")
		(2 "B.Cu" signal "BOTTOM")
		(9 "F.Adhes" user "F.Adhesive")
		(11 "B.Adhes" user "B.Adhesive")
		(13 "F.Paste" user "Package Geometry/Pastemask Top")
		(15 "B.Paste" user "Package Geometry/Pastemask Bottom")
		(5 "F.SilkS" user "Ref Des/Silkscreen Top")
		(7 "B.SilkS" user "Ref Des/Silkscreen Bottom")
		(1 "F.Mask" user "Board Geometry/Soldermask Top")
		(3 "B.Mask" user "Board Geometry/Soldermask Bottom")
		(17 "Dwgs.User" user "User.Drawings")
		(19 "Cmts.User" user "User.Comments")
		(21 "Eco1.User" user "User.Eco1")
		(23 "Eco2.User" user "User.Eco2")
		(25 "Edge.Cuts" user "Board Geometry/Outline")
		(27 "Margin" user)
		(31 "F.CrtYd" user "Package Geometry/Place Bound Top")
		(29 "B.CrtYd" user "Package Geometry/Place Bound Bottom")
		(35 "F.Fab" user "Ref Des/Assembly Top")
		(33 "B.Fab" user "Ref Des/Assembly Bottom")
	)
	(footprint ""
		(layer "F.Cu")
		(at 354.268278 -238.162338 -90)
		(property "Reference" "C1039"
			(at 0 0 270)
			(layer "F.SilkS")
			(hide yes)
			(effects
				(font
					(size 1.27 1.27)
				)
			)
		)
		(property "Value" ""
			(at 0 0 270)
			(layer "F.Fab")
			(effects
				(font
					(size 1.27 1.27)
				)
			)
		)
		(duplicate_pad_numbers_are_jumpers no)
		(fp_line
			(start -0.7874 0.4064)
			(end -0.7874 -0.4064)
			(stroke
				(width 0.1524)
				(type default)
			)
			(layer "F.SilkS")
		)
		(fp_line
			(start 0.7874 0.4064)
			(end -0.7874 0.4064)
			(stroke
				(width 0.1524)
				(type default)
			)
			(layer "F.SilkS")
		)
		(fp_line
			(start -0.7874 -0.4064)
			(end 0.7874 -0.4064)
			(stroke
				(width 0.1524)
				(type default)
			)
			(layer "F.SilkS")
		)
		(fp_line
			(start 0.7874 -0.4064)
			(end 0.7874 0.4064)
			(stroke
				(width 0.1524)
				(type default)
			)
			(layer "F.SilkS")
		)
		(fp_line
			(start -0.67945 0.3048)
			(end -0.67945 -0.305054)
			(stroke
				(width 0.1)
				(type default)
			)
			(layer "F.Fab")
		)
		(fp_line
			(start -0.12065 0.3048)
			(end -0.67945 0.3048)
			(stroke
				(width 0.1)
				(type default)
			)
			(layer "F.Fab")
		)
		(fp_line
			(start 0.120396 0.3048)
			(end 0.120396 0.2794)
			(stroke
				(width 0.1)
				(type default)
			)
			(layer "F.Fab")
		)
		(fp_line
			(start 0.67945 0.3048)
			(end 0.120396 0.3048)
			(stroke
				(width 0.1)
				(type default)
			)
			(layer "F.Fab")
		)
		(fp_line
			(start -0.12065 0.2794)
			(end -0.12065 0.3048)
			(stroke
				(width 0.1)
				(type default)
			)
			(layer "F.Fab")
		)
		(fp_line
			(start 0.120396 0.2794)
			(end -0.12065 0.2794)
			(stroke
				(width 0.1)
				(type default)
			)
			(layer "F.Fab")
		)
		(fp_line
			(start -0.12065 -0.2794)
			(end 0.12065 -0.2794)
			(stroke
				(width 0.1)
				(type default)
			)
			(layer "F.Fab")
		)
		(fp_line
			(start 0.12065 -0.2794)
			(end 0.12065 -0.3048)
			(stroke
				(width 0.1)
				(type default)
			)
			(layer "F.Fab")
		)
		(fp_line
			(start 0.12065 -0.3048)
			(end 0.67945 -0.3048)
			(stroke
				(width 0.1)
				(type default)
			)
			(layer "F.Fab")
		)
		(fp_line
			(start 0.67945 -0.3048)
			(end 0.67945 0.3048)
			(stroke
				(width 0.1)
				(type default)
			)
			(layer "F.Fab")
		)
		(fp_line
			(start -0.67945 -0.305054)
			(end -0.12065 -0.305054)
			(stroke
				(width 0.1)
				(type default)
			)
			(layer "F.Fab")
		)
		(fp_line
			(start -0.12065 -0.305054)
			(end -0.12065 -0.2794)
			(stroke
				(width 0.1)
				(type default)
			)
			(layer "F.Fab")
		)
		(pad "1" smd circle
			(at -0.40005 0 270)
			(size 0 0)
			(layers "F.Cu" "F.Mask" "F.Paste")
			(net "PVCCIN_CPU0")
		)
		(pad "2" smd circle
			(at 0.40005 0 270)
			(size 0 0)
			(layers "F.Cu" "F.Mask" "F.Paste")
			(net "GND")
		)
	)
	(footprint ""
		(layer "F.Cu")
		(at 21.176996 -98.171508)
		(property "Reference" "R3665"
			(at 0 0 0)
			(layer "F.SilkS")
			(hide yes)
			(effects
				(font
					(size 1.27 1.27)
				)
			)
		)
		(property "Value" ""
			(at 0 0 0)
			(layer "F.Fab")
			(effects
				(font
					(size 1.27 1.27)
				)
			)
		)
		(duplicate_pad_numbers_are_jumpers no)
		(fp_line
			(start -0.7874 -0.4064)
			(end 0.7874 -0.4064)
			(stroke
				(width 0.1524)
				(type default)
			)
			(layer "F.SilkS")
		)
		(fp_line
			(start -0.7874 0.4064)
			(end -0.7874 -0.4064)
			(stroke
				(width 0.1524)
				(type default)
			)
			(layer "F.SilkS")
		)
		(fp_line
			(start 0.7874 -0.4064)
			(end 0.7874 0.4064)
			(stroke
				(width 0.1524)
				(type default)
			)
			(layer "F.SilkS")
		)
		(fp_line
			(start 0.7874 0.4064)
			(end -0.7874 0.4064)
			(stroke
				(width 0.1524)
				(type default)
			)
			(layer "F.SilkS")
		)
		(fp_line
			(start -0.67945 -0.305054)
			(end -0.12065 -0.305054)
			(stroke
				(width 0.1)
				(type default)
			)
			(layer "F.Fab")
		)
		(fp_line
			(start -0.67945 0.3048)
			(end -0.67945 -0.305054)
			(stroke
				(width 0.1)
				(type default)
			)
			(layer "F.Fab")
		)
		(fp_line
			(start -0.12065 -0.305054)
			(end -0.12065 -0.2794)
			(stroke
				(width 0.1)
				(type default)
			)
			(layer "F.Fab")
		)
		(fp_line
			(start -0.12065 -0.2794)
			(end 0.12065 -0.2794)
			(stroke
				(width 0.1)
				(type default)
			)
			(layer "F.Fab")
		)
		(fp_line
			(start -0.12065 0.2794)
			(end -0.12065 0.3048)
			(stroke
				(width 0.1)
				(type default)
			)
			(layer "F.Fab")
		)
		(fp_line
			(start -0.12065 0.3048)
			(end -0.67945 0.3048)
			(stroke
				(width 0.1)
				(type default)
			)
			(layer "F.Fab")
		)
		(fp_line
			(start 0.120396 0.2794)
			(end -0.12065 0.2794)
			(stroke
				(width 0.1)
				(type default)
			)
			(layer "F.Fab")
		)
		(fp_line
			(start 0.120396 0.3048)
			(end 0.120396 0.2794)
			(stroke
				(width 0.1)
				(type default)
			)
			(layer "F.Fab")
		)
		(fp_line
			(start 0.12065 -0.3048)
			(end 0.67945 -0.3048)
			(stroke
				(width 0.1)
				(type default)
			)
			(layer "F.Fab")
		)
		(fp_line
			(start 0.12065 -0.2794)
			(end 0.12065 -0.3048)
			(stroke
				(width 0.1)
				(type default)
			)
			(layer "F.Fab")
		)
		(fp_line
			(start 0.67945 -0.3048)
			(end 0.67945 0.3048)
			(stroke
				(width 0.1)
				(type default)
			)
			(layer "F.Fab")
		)
		(fp_line
			(start 0.67945 0.3048)
			(end 0.120396 0.3048)
			(stroke
				(width 0.1)
				(type default)
			)
			(layer "F.Fab")
		)
		(pad "1" smd circle
			(at -0.40005 0)
			(size 0 0)
			(layers "F.Cu" "F.Mask" "F.Paste")
			(net "USB_HUB_PGANG")
		)
		(pad "2" smd circle
			(at 0.40005 0)
			(size 0 0)
			(layers "F.Cu" "F.Mask" "F.Paste")
			(net "GND")
		)
	)
)
